# T6G (Grand Teton) — schematic netlist excerpt (pin names and nets, part order shuffled) for the footprints in the layout excerpt that follows; sources: Cadence DE-HDL packaged netlist, KiCad conversion of 04192023_DAF0TMB3IC0_F0TG_MB_C_brd_V02_OCP.brd

C300  Q_CAP  0.1UF 10V 10% X7S  pkg C0201  page 334 : A = P0V9_CPU1_RT_2D ; B = GND
C2534  Q_CAP  22UF 4V 20% X6S  pkg C0402  page 70 : A = PVDDCR_SOC_P0 ; B = GND
R101  Q_RES  1K 1% EMPTY  pkg 0402LF  page 97 : A = P3V3 ; B = PWRGD_CHL_CPU0_DIMM

(kicad_pcb
	(version 20260206)
	(generator "pcbnew")
	(generator_version "10.0")
	(general
		(thickness 1.6)
		(legacy_teardrops no)
	)
	(paper "A4")
	(title_block
		(title "04192023_DAF0TMB3IC0_F0TG_MB_C_brd_V02_OCP.brd")
		(comment 1 "Grand Teton / footprints 6349-6352 of 8354")
	)
	(layers
		(0 "F.Cu" signal "TOP")
		(4 "In1.Cu" signal "GND")
		(6 "In2.Cu" signal "IN1")
		(8 "In3.Cu" signal "GND1")
		(10 "In4.Cu" signal "IN2")
		(12 "In5.Cu" signal "GND2")
		(14 "In6.Cu" signal "IN3")
		(16 "In7.Cu" signal "GND3")
		(18 "In8.Cu" signal "VCC")
		(20 "In9.Cu" signal "VCC1")
		(22 "In10.Cu" signal "GND4")
		(24 "In11.Cu" signal "IN4")
		(26 "In12.Cu" signal "GND5")
		(28 "In13.Cu" signal "IN5")
		(30 "In14.Cu" signal "GND6")
		(32 "In15.Cu" signal "IN6")
		(34 "In16.Cu" signal "GND7")
		(2 "B.Cu" signal "BOTTOM")
		(9 "F.Adhes" user "F.Adhesive")
		(11 "B.Adhes" user "B.Adhesive")
		(13 "F.Paste" user "Package Geometry/Pastemask Top")
		(15 "B.Paste" user "Package Geometry/Pastemask Bottom")
		(5 "F.SilkS" user "Ref Des/Silkscreen Top")
		(7 "B.SilkS" user "Ref Des/Silkscreen Bottom")
		(1 "F.Mask" user "Board Geometry/Soldermask Top")
		(3 "B.Mask" user "Board Geometry/Soldermask Bottom")
		(17 "Dwgs.User" user "User.Drawings")
		(19 "Cmts.User" user "User.Comments")
		(21 "Eco1.User" user "User.Eco1")
		(23 "Eco2.User" user "User.Eco2")
		(25 "Edge.Cuts" user "Board Geometry/Outline")
		(27 "Margin" user)
		(31 "F.CrtYd" user "Package Geometry/Place Bound Top")
		(29 "B.CrtYd" user "Package Geometry/Place Bound Bottom")
		(35 "F.Fab" user "Ref Des/Assembly Top")
		(33 "B.Fab" user "Ref Des/Assembly Bottom")
	)
	(footprint ""
		(layer "B.Cu")
		(at 450.84365 -193.99631)
		(property "Reference" "R101"
			(at 0 0 0)
			(layer "B.SilkS")
			(hide yes)
			(effects
				(font
					(size 1.27 1.27)
				)
				(justify mirror)
			)
		)
		(property "Value" ""
			(at 0 0 0)
			(layer "B.Fab")
			(effects
				(font
					(size 1.27 1.27)
				)
				(justify mirror)
			)
		)
		(duplicate_pad_numbers_are_jumpers no)
		(fp_line
			(start -0.7874 -0.4064)
			(end -0.7874 0.4064)
			(stroke
				(width 0.1524)
				(type default)
			)
			(layer "B.SilkS")
		)
		(fp_line
			(start -0.7874 0.4064)
			(end 0.7874 0.4064)
			(stroke
				(width 0.1524)
				(type default)
			)
			(layer "B.SilkS")
		)
		(fp_line
			(start 0.7874 -0.4064)
			(end -0.7874 -0.4064)
			(stroke
				(width 0.1524)
				(type default)
			)
			(layer "B.SilkS")
		)
		(fp_line
			(start 0.7874 0.4064)
			(end 0.7874 -0.4064)
			(stroke
				(width 0.1524)
				(type default)
			)
			(layer "B.SilkS")
		)
		(fp_line
			(start -0.67945 -0.3048)
			(end -0.67945 0.3048)
			(stroke
				(width 0.1)
				(type default)
			)
			(layer "B.Fab")
		)
		(fp_line
			(start -0.67945 0.3048)
			(end -0.120396 0.3048)
			(stroke
				(width 0.1)
				(type default)
			)
			(layer "B.Fab")
		)
		(fp_line
			(start -0.12065 -0.3048)
			(end -0.67945 -0.3048)
			(stroke
				(width 0.1)
				(type default)
			)
			(layer "B.Fab")
		)
		(fp_line
			(start -0.12065 -0.2794)
			(end -0.12065 -0.3048)
			(stroke
				(width 0.1)
				(type default)
			)
			(layer "B.Fab")
		)
		(fp_line
			(start -0.120396 0.2794)
			(end 0.12065 0.2794)
			(stroke
				(width 0.1)
				(type default)
			)
			(layer "B.Fab")
		)
		(fp_line
			(start -0.120396 0.3048)
			(end -0.120396 0.2794)
			(stroke
				(width 0.1)
				(type default)
			)
			(layer "B.Fab")
		)
		(fp_line
			(start 0.12065 -0.305054)
			(end 0.12065 -0.2794)
			(stroke
				(width 0.1)
				(type default)
			)
			(layer "B.Fab")
		)
		(fp_line
			(start 0.12065 -0.2794)
			(end -0.12065 -0.2794)
			(stroke
				(width 0.1)
				(type default)
			)
			(layer "B.Fab")
		)
		(fp_line
			(start 0.12065 0.2794)
			(end 0.12065 0.3048)
			(stroke
				(width 0.1)
				(type default)
			)
			(layer "B.Fab")
		)
		(fp_line
			(start 0.12065 0.3048)
			(end 0.67945 0.3048)
			(stroke
				(width 0.1)
				(type default)
			)
			(layer "B.Fab")
		)
		(fp_line
			(start 0.67945 -0.305054)
			(end 0.12065 -0.305054)
			(stroke
				(width 0.1)
				(type default)
			)
			(layer "B.Fab")
		)
		(fp_line
			(start 0.67945 0.3048)
			(end 0.67945 -0.305054)
			(stroke
				(width 0.1)
				(type default)
			)
			(layer "B.Fab")
		)
		(pad "1" smd circle
			(at 0.40005 0 180)
			(size 0 0)
			(layers "B.Cu" "B.Mask" "B.Paste")
			(net "P3V3")
		)
		(pad "2" smd circle
			(at -0.40005 0 180)
			(size 0 0)
			(layers "B.Cu" "B.Mask" "B.Paste")
			(net "PWRGD_CHL_CPU0_DIMM")
		)
	)
	(footprint ""
		(layer "B.Cu")
		(at 48.0568 -112.800384)
		(property "Reference" "ME16"
			(at 0 0 0)
			(layer "B.SilkS")
			(hide yes)
			(effects
				(font
					(size 1.27 1.27)
				)
				(justify mirror)
			)
		)
		(property "Value" ""
			(at 0 0 0)
			(layer "B.Fab")
			(effects
				(font
					(size 1.27 1.27)
				)
				(justify mirror)
			)
		)
		(duplicate_pad_numbers_are_jumpers no)
		(zone
			(layer "B.Cu")
			(hatch none 0.5)
			(connect_pads
				(clearance 0)
			)
			(min_thickness 0.25)
			(keepout
				(tracks allowed)
				(vias allowed)
				(pads allowed)
				(copperpour allowed)
				(footprints not_allowed)
			)
			(placement
				(enabled no)
				(sheetname "")
			)
			(fill
				(thermal_gap 0.5)
				(thermal_bridge_width 0.5)
				(island_removal_mode 0)
			)
			(polygon
				(pts
					(arc
						(start 58.05678 -112.800384)
						(mid 38.05682 -112.800384)
						(end 58.05678 -112.800384)
					)
				)
			)
		)
	)
	(footprint ""
		(layer "B.Cu")
		(at 373.329454 -254.19431)
		(property "Reference" "C2534"
			(at 0 0 0)
			(layer "B.SilkS")
			(hide yes)
			(effects
				(font
					(size 1.27 1.27)
				)
				(justify mirror)
			)
		)
		(property "Value" ""
			(at 0 0 0)
			(layer "B.Fab")
			(effects
				(font
					(size 1.27 1.27)
				)
				(justify mirror)
			)
		)
		(duplicate_pad_numbers_are_jumpers no)
		(fp_line
			(start -0.7874 -0.4064)
			(end -0.7874 0.4064)
			(stroke
				(width 0.1524)
				(type default)
			)
			(layer "B.SilkS")
		)
		(fp_line
			(start -0.7874 0.4064)
			(end 0.7874 0.4064)
			(stroke
				(width 0.1524)
				(type default)
			)
			(layer "B.SilkS")
		)
		(fp_line
			(start 0.7874 -0.4064)
			(end -0.7874 -0.4064)
			(stroke
				(width 0.1524)
				(type default)
			)
			(layer "B.SilkS")
		)
		(fp_line
			(start 0.7874 0.4064)
			(end 0.7874 -0.4064)
			(stroke
				(width 0.1524)
				(type default)
			)
			(layer "B.SilkS")
		)
		(fp_line
			(start -0.67945 -0.3048)
			(end -0.67945 0.3048)
			(stroke
				(width 0.1)
				(type default)
			)
			(layer "B.Fab")
		)
		(fp_line
			(start -0.67945 0.3048)
			(end -0.120396 0.3048)
			(stroke
				(width 0.1)
				(type default)
			)
			(layer "B.Fab")
		)
		(fp_line
			(start -0.12065 -0.3048)
			(end -0.67945 -0.3048)
			(stroke
				(width 0.1)
				(type default)
			)
			(layer "B.Fab")
		)
		(fp_line
			(start -0.12065 -0.2794)
			(end -0.12065 -0.3048)
			(stroke
				(width 0.1)
				(type default)
			)
			(layer "B.Fab")
		)
		(fp_line
			(start -0.120396 0.2794)
			(end 0.12065 0.2794)
			(stroke
				(width 0.1)
				(type default)
			)
			(layer "B.Fab")
		)
		(fp_line
			(start -0.120396 0.3048)
			(end -0.120396 0.2794)
			(stroke
				(width 0.1)
				(type default)
			)
			(layer "B.Fab")
		)
		(fp_line
			(start 0.12065 -0.305054)
			(end 0.12065 -0.2794)
			(stroke
				(width 0.1)
				(type default)
			)
			(layer "B.Fab")
		)
		(fp_line
			(start 0.12065 -0.2794)
			(end -0.12065 -0.2794)
			(stroke
				(width 0.1)
				(type default)
			)
			(layer "B.Fab")
		)
		(fp_line
			(start 0.12065 0.2794)
			(end 0.12065 0.3048)
			(stroke
				(width 0.1)
				(type default)
			)
			(layer "B.Fab")
		)
		(fp_line
			(start 0.12065 0.3048)
			(end 0.67945 0.3048)
			(stroke
				(width 0.1)
				(type default)
			)
			(layer "B.Fab")
		)
		(fp_line
			(start 0.67945 -0.305054)
			(end 0.12065 -0.305054)
			(stroke
				(width 0.1)
				(type default)
			)
			(layer "B.Fab")
		)
		(fp_line
			(start 0.67945 0.3048)
			(end 0.67945 -0.305054)
			(stroke
				(width 0.1)
				(type default)
			)
			(layer "B.Fab")
		)
		(pad "1" smd circle
			(at 0.40005 0 180)
			(size 0 0)
			(layers "B.Cu" "B.Mask" "B.Paste")
			(net "PVDDCR_SOC_P0")
		)
		(pad "2" smd circle
			(at -0.40005 0 180)
			(size 0 0)
			(layers "B.Cu" "B.Mask" "B.Paste")
			(net "GND")
		)
	)
	(footprint ""
		(layer "B.Cu")
		(at 91.906344 -386.766562 90)
		(property "Reference" "C300"
			(at 0 0 90)
			(layer "B.SilkS")
			(hide yes)
			(effects
				(font
					(size 1.27 1.27)
				)
				(justify mirror)
			)
		)
		(property "Value" ""
			(at 0 0 90)
			(layer "B.Fab")
			(effects
				(font
					(size 1.27 1.27)
				)
				(justify mirror)
			)
		)
		(duplicate_pad_numbers_are_jumpers no)
		(fp_line
			(start 0.299974 -0.150114)
			(end -0.299974 -0.150114)
			(stroke
				(width 0.1)
				(type default)
			)
			(layer "B.Fab")
		)
		(fp_line
			(start -0.299974 -0.150114)
			(end -0.299974 0.150114)
			(stroke
				(width 0.1)
				(type default)
			)
			(layer "B.Fab")
		)
		(fp_line
			(start 0.299974 0.150114)
			(end 0.299974 -0.150114)
			(stroke
				(width 0.1)
				(type default)
			)
			(layer "B.Fab")
		)
		(fp_line
			(start -0.299974 0.150114)
			(end 0.299974 0.150114)
			(stroke
				(width 0.1)
				(type default)
			)
			(layer "B.Fab")
		)
		(pad "1" smd rect
			(at 0.2667 0 270)
			(size 0.3048 0.381)
			(layers "B.Cu" "B.Mask" "B.Paste")
			(net "P0V9_CPU1_RT_2D")
		)
		(pad "2" smd rect
			(at -0.2667 0 270)
			(size 0.3048 0.381)
			(layers "B.Cu" "B.Mask" "B.Paste")
			(net "GND")
		)
	)
)
